(kicad_pcb
	(version 20260206)
	(generator "pcbnew")
	(generator_version "10.0")
	(general
		(thickness 1.6)
		(legacy_teardrops no)
	)
	(paper "A4")
	(title_block
		(title "fcb — 12433-1M.1206WZS1330.brd")
		(comment 1 "Open Vault / Knox (Wiwynn) / footprints 234-241 of 495")
	)
	(layers
		(0 "F.Cu" signal "TOP")
		(4 "In1.Cu" signal "L2GND")
		(6 "In2.Cu" signal "L3VCC")
		(2 "B.Cu" signal "BOTTOM")
		(9 "F.Adhes" user "F.Adhesive")
		(11 "B.Adhes" user "B.Adhesive")
		(13 "F.Paste" user "Package Geometry/Pastemask Top")
		(15 "B.Paste" user "Package Geometry/Pastemask Bottom")
		(5 "F.SilkS" user "Ref Des/Silkscreen Top")
		(7 "B.SilkS" user "Ref Des/Silkscreen Bottom")
		(1 "F.Mask" user "Board Geometry/Soldermask Top")
		(3 "B.Mask" user "Board Geometry/Soldermask Bottom")
		(17 "Dwgs.User" user "User.Drawings")
		(19 "Cmts.User" user "User.Comments")
		(21 "Eco1.User" user "User.Eco1")
		(23 "Eco2.User" user "User.Eco2")
		(25 "Edge.Cuts" user "Board Geometry/Outline")
		(27 "Margin" user)
		(31 "F.CrtYd" user "Package Geometry/Place Bound Top")
		(29 "B.CrtYd" user "Package Geometry/Place Bound Bottom")
		(35 "F.Fab" user "Ref Des/Assembly Top")
		(33 "B.Fab" user "Ref Des/Assembly Bottom")
	)
	(footprint ""
		(layer "F.Cu")
		(at 19.9644 -145.4912 180)
		(property "Reference" "PR114"
			(at 0 0 180)
			(layer "F.SilkS")
			(hide yes)
			(effects
				(font
					(size 1.27 1.27)
				)
			)
		)
		(property "Value" "20KR2F-L-GP"
			(at 0.064008 -3.993896 180)
			(unlocked yes)
			(layer "F.Fab")
			(hide yes)
			(effects
				(font
					(size 1.016 1.016)
					(thickness 0.1524)
				)
			)
		)
		(property "Device Type" "R402H16"
			(at 0.064008 -5.517896 180)
			(unlocked yes)
			(layer "F.Fab")
			(hide yes)
			(effects
				(font
					(size 1.016 1.016)
					(thickness 0.1524)
				)
			)
		)
		(duplicate_pad_numbers_are_jumpers no)
		(fp_line
			(start 0.508 -0.9398)
			(end -0.508 -0.9398)
			(stroke
				(width 0.1524)
				(type default)
			)
			(layer "F.SilkS")
		)
		(fp_line
			(start -0.508 -0.9398)
			(end -0.508 0.9398)
			(stroke
				(width 0.1524)
				(type default)
			)
			(layer "F.SilkS")
		)
		(fp_rect
			(start -0.508 0.9398)
			(end 0.508 -0.9398)
			(stroke
				(width 0)
				(type default)
			)
			(fill no)
			(layer "F.CrtYd")
		)
		(fp_rect
			(start -0.508 0.9398)
			(end 0.508 -0.9398)
			(stroke
				(width 0)
				(type default)
			)
			(fill no)
			(layer "F.Fab")
		)
		(pad "1" smd custom
			(at 0 -0.4445 180)
			(size 0.1397 0.1397)
			(layers "F.Cu" "F.Mask" "F.Paste")
			(net "P12VU_2490_PROG")
			(options
				(clearance outline)
				(anchor circle)
			)
			(primitives
				(gr_poly
					(pts
						(arc
							(start -0.1778 -0.2794)
							(mid -0.249642 -0.249642)
							(end -0.2794 -0.1778)
						)
						(arc
							(start -0.2794 0.1778)
							(mid -0.249642 0.249642)
							(end -0.1778 0.2794)
						)
						(arc
							(start 0.1778 0.2794)
							(mid 0.249642 0.249642)
							(end 0.2794 0.1778)
						)
						(arc
							(start 0.2794 -0.1778)
							(mid 0.249642 -0.249642)
							(end 0.1778 -0.2794)
						)
					)
					(width 0)
					(fill yes)
				)
			)
		)
		(pad "2" smd custom
			(at 0 0.4445 180)
			(size 0.1397 0.1397)
			(layers "F.Cu" "F.Mask" "F.Paste")
			(net "GND")
			(options
				(clearance outline)
				(anchor circle)
			)
			(primitives
				(gr_poly
					(pts
						(arc
							(start -0.1778 -0.2794)
							(mid -0.249642 -0.249642)
							(end -0.2794 -0.1778)
						)
						(arc
							(start -0.2794 0.1778)
							(mid -0.249642 0.249642)
							(end -0.1778 0.2794)
						)
						(arc
							(start 0.1778 0.2794)
							(mid 0.249642 0.249642)
							(end 0.2794 0.1778)
						)
						(arc
							(start 0.2794 -0.1778)
							(mid 0.249642 -0.249642)
							(end 0.1778 -0.2794)
						)
					)
					(width 0)
					(fill yes)
				)
			)
		)
	)
	(footprint ""
		(layer "F.Cu")
		(at 18.415 -109.5502 90)
		(property "Reference" "PR118"
			(at 0 0 90)
			(layer "F.SilkS")
			(hide yes)
			(effects
				(font
					(size 1.27 1.27)
				)
			)
		)
		(property "Value" "10R2F-L-GP"
			(at 0.064008 -3.993896 90)
			(unlocked yes)
			(layer "F.Fab")
			(hide yes)
			(effects
				(font
					(size 1.016 1.016)
					(thickness 0.1524)
				)
			)
		)
		(property "Device Type" "R402H14"
			(at 0.064008 -5.517896 90)
			(unlocked yes)
			(layer "F.Fab")
			(hide yes)
			(effects
				(font
					(size 1.016 1.016)
					(thickness 0.1524)
				)
			)
		)
		(duplicate_pad_numbers_are_jumpers no)
		(fp_line
			(start 0.508 -0.9398)
			(end -0.508 -0.9398)
			(stroke
				(width 0.1524)
				(type default)
			)
			(layer "F.SilkS")
		)
		(fp_line
			(start -0.508 -0.9398)
			(end -0.508 0.9398)
			(stroke
				(width 0.1524)
				(type default)
			)
			(layer "F.SilkS")
		)
		(fp_rect
			(start -0.508 0.9398)
			(end 0.508 -0.9398)
			(stroke
				(width 0)
				(type default)
			)
			(fill no)
			(layer "F.CrtYd")
		)
		(fp_rect
			(start -0.508 0.9398)
			(end 0.508 -0.9398)
			(stroke
				(width 0)
				(type default)
			)
			(fill no)
			(layer "F.Fab")
		)
		(pad "1" smd custom
			(at 0 -0.4445 90)
			(size 0.1397 0.1397)
			(layers "F.Cu" "F.Mask" "F.Paste")
			(net "P12VU_2490_GATE_DRV_2")
			(options
				(clearance outline)
				(anchor circle)
			)
			(primitives
				(gr_poly
					(pts
						(arc
							(start -0.1778 -0.2794)
							(mid -0.249642 -0.249642)
							(end -0.2794 -0.1778)
						)
						(arc
							(start -0.2794 0.1778)
							(mid -0.249642 0.249642)
							(end -0.1778 0.2794)
						)
						(arc
							(start 0.1778 0.2794)
							(mid 0.249642 0.249642)
							(end 0.2794 0.1778)
						)
						(arc
							(start 0.2794 -0.1778)
							(mid 0.249642 -0.249642)
							(end 0.1778 -0.2794)
						)
					)
					(width 0)
					(fill yes)
				)
			)
		)
		(pad "2" smd custom
			(at 0 0.4445 90)
			(size 0.1397 0.1397)
			(layers "F.Cu" "F.Mask" "F.Paste")
			(net "P12VU_2490_GATE")
			(options
				(clearance outline)
				(anchor circle)
			)
			(primitives
				(gr_poly
					(pts
						(arc
							(start -0.1778 -0.2794)
							(mid -0.249642 -0.249642)
							(end -0.2794 -0.1778)
						)
						(arc
							(start -0.2794 0.1778)
							(mid -0.249642 0.249642)
							(end -0.1778 0.2794)
						)
						(arc
							(start 0.1778 0.2794)
							(mid 0.249642 0.249642)
							(end 0.2794 0.1778)
						)
						(arc
							(start 0.2794 -0.1778)
							(mid 0.249642 -0.249642)
							(end 0.1778 -0.2794)
						)
					)
					(width 0)
					(fill yes)
				)
			)
		)
	)
	(footprint ""
		(layer "F.Cu")
		(at 12.064492 -61.391546)
		(property "Reference" "C32"
			(at 0 0 0)
			(layer "F.SilkS")
			(hide yes)
			(effects
				(font
					(size 1.27 1.27)
				)
			)
		)
		(property "Value" "SC1U25V3KX-1-GP"
			(at 0 -2.8194 0)
			(unlocked yes)
			(layer "F.Fab")
			(hide yes)
			(effects
				(font
					(size 1.016 1.016)
					(thickness 0.1524)
				)
			)
		)
		(property "Device Type" "C603H36"
			(at 0 -4.3434 0)
			(unlocked yes)
			(layer "F.Fab")
			(hide yes)
			(effects
				(font
					(size 1.016 1.016)
					(thickness 0.1524)
				)
			)
		)
		(duplicate_pad_numbers_are_jumpers no)
		(fp_line
			(start 0.508 0)
			(end -0.508 0)
			(stroke
				(width 0.2032)
				(type default)
			)
			(layer "F.SilkS")
		)
		(fp_rect
			(start -0.5842 1.3335)
			(end 0.5842 -1.3335)
			(stroke
				(width 0)
				(type default)
			)
			(fill no)
			(layer "F.CrtYd")
		)
		(fp_rect
			(start -0.5842 1.3335)
			(end 0.5842 -1.3335)
			(stroke
				(width 0)
				(type default)
			)
			(fill no)
			(layer "F.Fab")
		)
		(pad "1" smd custom
			(at 0 -0.762)
			(size 0.2159 0.2159)
			(layers "F.Cu" "F.Mask" "F.Paste")
			(net "P12V")
			(options
				(clearance outline)
				(anchor circle)
			)
			(primitives
				(gr_poly
					(pts
						(arc
							(start -0.3302 -0.4318)
							(mid -0.402042 -0.402042)
							(end -0.4318 -0.3302)
						)
						(arc
							(start -0.4318 0.3302)
							(mid -0.402042 0.402042)
							(end -0.3302 0.4318)
						)
						(arc
							(start 0.3302 0.4318)
							(mid 0.402042 0.402042)
							(end 0.4318 0.3302)
						)
						(arc
							(start 0.4318 -0.3302)
							(mid 0.402042 -0.402042)
							(end 0.3302 -0.4318)
						)
					)
					(width 0)
					(fill yes)
				)
			)
		)
		(pad "2" smd custom
			(at 0 0.762)
			(size 0.2159 0.2159)
			(layers "F.Cu" "F.Mask" "F.Paste")
			(net "GND")
			(options
				(clearance outline)
				(anchor circle)
			)
			(primitives
				(gr_poly
					(pts
						(arc
							(start -0.3302 -0.4318)
							(mid -0.402042 -0.402042)
							(end -0.4318 -0.3302)
						)
						(arc
							(start -0.4318 0.3302)
							(mid -0.402042 0.402042)
							(end -0.3302 0.4318)
						)
						(arc
							(start 0.3302 0.4318)
							(mid 0.402042 0.402042)
							(end 0.4318 0.3302)
						)
						(arc
							(start 0.4318 -0.3302)
							(mid 0.402042 -0.402042)
							(end 0.3302 -0.4318)
						)
					)
					(width 0)
					(fill yes)
				)
			)
		)
	)
	(footprint ""
		(layer "F.Cu")
		(at 34.741866 -137.508234 180)
		(property "Reference" "PR105"
			(at 0 0 180)
			(layer "F.SilkS")
			(hide yes)
			(effects
				(font
					(size 1.27 1.27)
				)
			)
		)
		(property "Value" "2K7R2F-GP"
			(at 0.064008 -3.993896 180)
			(unlocked yes)
			(layer "F.Fab")
			(hide yes)
			(effects
				(font
					(size 1.016 1.016)
					(thickness 0.1524)
				)
			)
		)
		(property "Device Type" "R402H16"
			(at 0.064008 -5.517896 180)
			(unlocked yes)
			(layer "F.Fab")
			(hide yes)
			(effects
				(font
					(size 1.016 1.016)
					(thickness 0.1524)
				)
			)
		)
		(duplicate_pad_numbers_are_jumpers no)
		(fp_line
			(start 0.508 -0.9398)
			(end -0.508 -0.9398)
			(stroke
				(width 0.1524)
				(type default)
			)
			(layer "F.SilkS")
		)
		(fp_line
			(start -0.508 -0.9398)
			(end -0.508 0.9398)
			(stroke
				(width 0.1524)
				(type default)
			)
			(layer "F.SilkS")
		)
		(fp_rect
			(start -0.508 0.9398)
			(end 0.508 -0.9398)
			(stroke
				(width 0)
				(type default)
			)
			(fill no)
			(layer "F.CrtYd")
		)
		(fp_rect
			(start -0.508 0.9398)
			(end 0.508 -0.9398)
			(stroke
				(width 0)
				(type default)
			)
			(fill no)
			(layer "F.Fab")
		)
		(pad "1" smd custom
			(at 0 -0.4445 180)
			(size 0.1397 0.1397)
			(layers "F.Cu" "F.Mask" "F.Paste")
			(net "P12VL")
			(options
				(clearance outline)
				(anchor circle)
			)
			(primitives
				(gr_poly
					(pts
						(arc
							(start -0.1778 -0.2794)
							(mid -0.249642 -0.249642)
							(end -0.2794 -0.1778)
						)
						(arc
							(start -0.2794 0.1778)
							(mid -0.249642 0.249642)
							(end -0.1778 0.2794)
						)
						(arc
							(start 0.1778 0.2794)
							(mid 0.249642 0.249642)
							(end 0.2794 0.1778)
						)
						(arc
							(start 0.2794 -0.1778)
							(mid 0.249642 -0.249642)
							(end 0.1778 -0.2794)
						)
					)
					(width 0)
					(fill yes)
				)
			)
		)
		(pad "2" smd custom
			(at 0 0.4445 180)
			(size 0.1397 0.1397)
			(layers "F.Cu" "F.Mask" "F.Paste")
			(net "P12VL_2490_PG")
			(options
				(clearance outline)
				(anchor circle)
			)
			(primitives
				(gr_poly
					(pts
						(arc
							(start -0.1778 -0.2794)
							(mid -0.249642 -0.249642)
							(end -0.2794 -0.1778)
						)
						(arc
							(start -0.2794 0.1778)
							(mid -0.249642 0.249642)
							(end -0.1778 0.2794)
						)
						(arc
							(start 0.1778 0.2794)
							(mid 0.249642 0.249642)
							(end 0.2794 0.1778)
						)
						(arc
							(start 0.2794 -0.1778)
							(mid 0.249642 -0.249642)
							(end 0.1778 -0.2794)
						)
					)
					(width 0)
					(fill yes)
				)
			)
		)
	)
	(footprint ""
		(layer "F.Cu")
		(at 25.018238 -481.735892 -90)
		(property "Reference" "F6"
			(at 0 0 270)
			(layer "F.SilkS")
			(hide yes)
			(effects
				(font
					(size 1.27 1.27)
				)
			)
		)
		(property "Value" "FUSE-3A15V-GP"
			(at 0.2286 -10.5918 270)
			(unlocked yes)
			(layer "F.Fab")
			(hide yes)
			(effects
				(font
					(size 1.016 1.016)
					(thickness 0.1524)
				)
			)
		)
		(property "Device Type" "FUSE-7452-UH50"
			(at 0.2286 -12.4968 270)
			(unlocked yes)
			(layer "F.Fab")
			(hide yes)
			(effects
				(font
					(size 1.016 1.016)
					(thickness 0.1524)
				)
			)
		)
		(duplicate_pad_numbers_are_jumpers no)
		(fp_line
			(start -4.9276 2.921)
			(end -4.9276 -2.921)
			(stroke
				(width 0.1524)
				(type default)
			)
			(layer "F.SilkS")
		)
		(fp_line
			(start 4.9276 2.921)
			(end -4.9276 2.921)
			(stroke
				(width 0.1524)
				(type default)
			)
			(layer "F.SilkS")
		)
		(fp_line
			(start -4.9276 -2.921)
			(end 4.9276 -2.921)
			(stroke
				(width 0.1524)
				(type default)
			)
			(layer "F.SilkS")
		)
		(fp_line
			(start 4.9276 -2.921)
			(end 4.9276 2.921)
			(stroke
				(width 0.1524)
				(type default)
			)
			(layer "F.SilkS")
		)
		(fp_poly
			(pts
				(xy -5.08 3.0988) (xy 5.08 3.0988) (xy 5.08 -3.0988) (xy -5.08 -3.0988)
			)
			(stroke
				(width 0)
				(type default)
			)
			(fill no)
			(layer "F.CrtYd")
		)
		(fp_poly
			(pts
				(xy -5.08 -3.0988) (xy 5.08 -3.0988) (xy 5.08 3.0988) (xy -5.08 3.0988)
			)
			(stroke
				(width 0)
				(type default)
			)
			(fill no)
			(layer "F.Fab")
		)
		(pad "1" smd rect
			(at -3.4036 0 270)
			(size 2.2098 5.2832)
			(layers "F.Cu" "F.Mask" "F.Paste")
			(net "P12V_FAN1")
		)
		(pad "2" smd rect
			(at 3.4036 0 270)
			(size 2.2098 5.2832)
			(layers "F.Cu" "F.Mask" "F.Paste")
			(net "P12V")
		)
	)
	(footprint ""
		(layer "F.Cu")
		(at 17.831308 -287.451038)
		(property "Reference" "D9"
			(at 0 0 0)
			(layer "F.SilkS")
			(hide yes)
			(effects
				(font
					(size 1.27 1.27)
				)
			)
		)
		(property "Value" "BAS16H-GP"
			(at 0 -5.5372 0)
			(unlocked yes)
			(layer "F.Fab")
			(hide yes)
			(effects
				(font
					(size 1.016 1.016)
					(thickness 0.1524)
				)
			)
		)
		(property "Device Type" "SOD123AKH48"
			(at 0 -7.0612 0)
			(unlocked yes)
			(layer "F.Fab")
			(hide yes)
			(effects
				(font
					(size 1.016 1.016)
					(thickness 0.1524)
				)
			)
		)
		(duplicate_pad_numbers_are_jumpers no)
		(fp_line
			(start -1.016 -2.667)
			(end -1.016 2.667)
			(stroke
				(width 0.1524)
				(type default)
			)
			(layer "F.SilkS")
		)
		(fp_line
			(start -1.016 2.667)
			(end 1.016 2.667)
			(stroke
				(width 0.1524)
				(type default)
			)
			(layer "F.SilkS")
		)
		(fp_line
			(start 0.889 2.921)
			(end -0.889 2.921)
			(stroke
				(width 0.508)
				(type default)
			)
			(layer "F.SilkS")
		)
		(fp_line
			(start 1.016 -2.667)
			(end -1.016 -2.667)
			(stroke
				(width 0.1524)
				(type default)
			)
			(layer "F.SilkS")
		)
		(fp_line
			(start 1.016 2.667)
			(end 1.016 -2.667)
			(stroke
				(width 0.1524)
				(type default)
			)
			(layer "F.SilkS")
		)
		(fp_rect
			(start -1.143 3.175)
			(end 1.143 -2.794)
			(stroke
				(width 0)
				(type default)
			)
			(fill no)
			(layer "F.CrtYd")
		)
		(fp_poly
			(pts
				(xy -1.143 -2.794) (xy 1.143 -2.794) (xy 1.143 3.175) (xy -1.143 3.175)
			)
			(stroke
				(width 0)
				(type default)
			)
			(fill no)
			(layer "F.Fab")
		)
		(pad "A" smd rect
			(at 0 -1.6891)
			(size 0.889 1.397)
			(layers "F.Cu" "F.Mask" "F.Paste")
			(net "FAN_TACH3")
		)
		(pad "K" smd rect
			(at 0 1.6891)
			(size 0.889 1.397)
			(layers "F.Cu" "F.Mask" "F.Paste")
			(net "P12V")
		)
	)
	(footprint ""
		(layer "F.Cu")
		(at 40.8178 -156.4386 180)
		(property "Reference" "TP17"
			(at 0 0 180)
			(layer "F.SilkS")
			(hide yes)
			(effects
				(font
					(size 1.27 1.27)
				)
			)
		)
		(property "Value" "TPAD32-GP"
			(at 0 -3.166364 180)
			(unlocked yes)
			(layer "F.Fab")
			(hide yes)
			(effects
				(font
					(size 1.016 1.016)
					(thickness 0.1524)
				)
			)
		)
		(property "Device Type" "TPAD32"
			(at 0 -4.690618 180)
			(unlocked yes)
			(layer "F.Fab")
			(hide yes)
			(effects
				(font
					(size 1.016 1.016)
					(thickness 0.1524)
				)
			)
		)
		(duplicate_pad_numbers_are_jumpers no)
		(fp_poly
			(pts
				(arc
					(start -0.7112 0)
					(mid 0.7112 0)
					(end -0.7112 0)
				)
			)
			(stroke
				(width 0)
				(type default)
			)
			(fill no)
			(layer "F.CrtYd")
		)
		(fp_poly
			(pts
				(arc
					(start -0.7112 0)
					(mid 0.7112 0)
					(end -0.7112 0)
				)
			)
			(stroke
				(width 0)
				(type default)
			)
			(fill no)
			(layer "F.Fab")
		)
		(pad "1" smd circle
			(at 0 0 180)
			(size 0.8128 0.8128)
			(layers "F.Cu" "F.Mask" "F.Paste")
			(net "NCT7904_PROCHOT")
		)
	)
	(footprint ""
		(layer "F.Cu")
		(at 7.112 -452.374 90)
		(property "Reference" "D11"
			(at 0 0 90)
			(layer "F.SilkS")
			(hide yes)
			(effects
				(font
					(size 1.27 1.27)
				)
			)
		)
		(property "Value" "BAS16H-GP"
			(at 0 -5.5372 90)
			(unlocked yes)
			(layer "F.Fab")
			(hide yes)
			(effects
				(font
					(size 1.016 1.016)
					(thickness 0.1524)
				)
			)
		)
		(property "Device Type" "SOD123AKH48"
			(at 0 -7.0612 90)
			(unlocked yes)
			(layer "F.Fab")
			(hide yes)
			(effects
				(font
					(size 1.016 1.016)
					(thickness 0.1524)
				)
			)
		)
		(duplicate_pad_numbers_are_jumpers no)
		(fp_line
			(start 1.016 -2.667)
			(end -1.016 -2.667)
			(stroke
				(width 0.1524)
				(type default)
			)
			(layer "F.SilkS")
		)
		(fp_line
			(start -1.016 -2.667)
			(end -1.016 2.667)
			(stroke
				(width 0.1524)
				(type default)
			)
			(layer "F.SilkS")
		)
		(fp_line
			(start 1.016 2.667)
			(end 1.016 -2.667)
			(stroke
				(width 0.1524)
				(type default)
			)
			(layer "F.SilkS")
		)
		(fp_line
			(start -1.016 2.667)
			(end 1.016 2.667)
			(stroke
				(width 0.1524)
				(type default)
			)
			(layer "F.SilkS")
		)
		(fp_line
			(start 0.889 2.921)
			(end -0.889 2.921)
			(stroke
				(width 0.508)
				(type default)
			)
			(layer "F.SilkS")
		)
		(fp_rect
			(start -1.143 3.175)
			(end 1.143 -2.794)
			(stroke
				(width 0)
				(type default)
			)
			(fill no)
			(layer "F.CrtYd")
		)
		(fp_poly
			(pts
				(xy -1.143 -2.794) (xy 1.143 -2.794) (xy 1.143 3.175) (xy -1.143 3.175)
			)
			(stroke
				(width 0)
				(type default)
			)
			(fill no)
			(layer "F.Fab")
		)
		(pad "A" smd rect
			(at 0 -1.6891 90)
			(size 0.889 1.397)
			(layers "F.Cu" "F.Mask" "F.Paste")
			(net "FAN_TACH1")
		)
		(pad "K" smd rect
			(at 0 1.6891 90)
			(size 0.889 1.397)
			(layers "F.Cu" "F.Mask" "F.Paste")
			(net "P12V")
		)
	)
)
